(kicad_pcb
	(version 20260206)
	(generator "pcbnew")
	(generator_version "10.0")
	(general
		(thickness 1.6)
		(legacy_teardrops no)
	)
	(paper "A4")
	(title_block
		(title "03242023_DA0F0TMBIJ0_F0T_Motherboard_J_brd_V01_OCP.brd")
		(comment 1 "Grand Teton / footprints 5144-5150 of 6105")
	)
	(layers
		(0 "F.Cu" signal "TOP")
		(4 "In1.Cu" signal "GND")
		(6 "In2.Cu" signal "IN1")
		(8 "In3.Cu" signal "GND1")
		(10 "In4.Cu" signal "IN2")
		(12 "In5.Cu" signal "GND2")
		(14 "In6.Cu" signal "IN3")
		(16 "In7.Cu" signal "GND3")
		(18 "In8.Cu" signal "VCC")
		(20 "In9.Cu" signal "VCC1")
		(22 "In10.Cu" signal "GND4")
		(24 "In11.Cu" signal "IN4")
		(26 "In12.Cu" signal "GND5")
		(28 "In13.Cu" signal "IN5")
		(30 "In14.Cu" signal "GND6")
		(32 "In15.Cu" signal "IN6")
		(34 "In16.Cu" signal "GND7")
		(2 "B.Cu" signal "BOTTOM")
		(9 "F.Adhes" user "F.Adhesive")
		(11 "B.Adhes" user "B.Adhesive")
		(13 "F.Paste" user "Package Geometry/Pastemask Top")
		(15 "B.Paste" user "Package Geometry/Pastemask Bottom")
		(5 "F.SilkS" user "Ref Des/Silkscreen Top")
		(7 "B.SilkS" user "Ref Des/Silkscreen Bottom")
		(1 "F.Mask" user "Board Geometry/Soldermask Top")
		(3 "B.Mask" user "Board Geometry/Soldermask Bottom")
		(17 "Dwgs.User" user "User.Drawings")
		(19 "Cmts.User" user "User.Comments")
		(21 "Eco1.User" user "User.Eco1")
		(23 "Eco2.User" user "User.Eco2")
		(25 "Edge.Cuts" user "Board Geometry/Outline")
		(27 "Margin" user)
		(31 "F.CrtYd" user "Package Geometry/Place Bound Top")
		(29 "B.CrtYd" user "Package Geometry/Place Bound Bottom")
		(35 "F.Fab" user "Ref Des/Assembly Top")
		(33 "B.Fab" user "Ref Des/Assembly Bottom")
	)
	(footprint ""
		(layer "B.Cu")
		(at 257.91287 -318.582802)
		(property "Reference" "R32"
			(at 0 0 0)
			(layer "B.SilkS")
			(hide yes)
			(effects
				(font
					(size 1.27 1.27)
				)
				(justify mirror)
			)
		)
		(property "Value" ""
			(at 0 0 0)
			(layer "B.Fab")
			(effects
				(font
					(size 1.27 1.27)
				)
				(justify mirror)
			)
		)
		(duplicate_pad_numbers_are_jumpers no)
		(fp_line
			(start -0.7874 -0.4064)
			(end -0.7874 0.4064)
			(stroke
				(width 0.1524)
				(type default)
			)
			(layer "B.SilkS")
		)
		(fp_line
			(start -0.7874 0.4064)
			(end 0.7874 0.4064)
			(stroke
				(width 0.1524)
				(type default)
			)
			(layer "B.SilkS")
		)
		(fp_line
			(start 0.7874 -0.4064)
			(end -0.7874 -0.4064)
			(stroke
				(width 0.1524)
				(type default)
			)
			(layer "B.SilkS")
		)
		(fp_line
			(start 0.7874 0.4064)
			(end 0.7874 -0.4064)
			(stroke
				(width 0.1524)
				(type default)
			)
			(layer "B.SilkS")
		)
		(fp_line
			(start -0.67945 -0.3048)
			(end -0.67945 0.3048)
			(stroke
				(width 0.1)
				(type default)
			)
			(layer "B.Fab")
		)
		(fp_line
			(start -0.67945 0.3048)
			(end -0.120396 0.3048)
			(stroke
				(width 0.1)
				(type default)
			)
			(layer "B.Fab")
		)
		(fp_line
			(start -0.12065 -0.3048)
			(end -0.67945 -0.3048)
			(stroke
				(width 0.1)
				(type default)
			)
			(layer "B.Fab")
		)
		(fp_line
			(start -0.12065 -0.2794)
			(end -0.12065 -0.3048)
			(stroke
				(width 0.1)
				(type default)
			)
			(layer "B.Fab")
		)
		(fp_line
			(start -0.120396 0.2794)
			(end 0.12065 0.2794)
			(stroke
				(width 0.1)
				(type default)
			)
			(layer "B.Fab")
		)
		(fp_line
			(start -0.120396 0.3048)
			(end -0.120396 0.2794)
			(stroke
				(width 0.1)
				(type default)
			)
			(layer "B.Fab")
		)
		(fp_line
			(start 0.12065 -0.305054)
			(end 0.12065 -0.2794)
			(stroke
				(width 0.1)
				(type default)
			)
			(layer "B.Fab")
		)
		(fp_line
			(start 0.12065 -0.2794)
			(end -0.12065 -0.2794)
			(stroke
				(width 0.1)
				(type default)
			)
			(layer "B.Fab")
		)
		(fp_line
			(start 0.12065 0.2794)
			(end 0.12065 0.3048)
			(stroke
				(width 0.1)
				(type default)
			)
			(layer "B.Fab")
		)
		(fp_line
			(start 0.12065 0.3048)
			(end 0.67945 0.3048)
			(stroke
				(width 0.1)
				(type default)
			)
			(layer "B.Fab")
		)
		(fp_line
			(start 0.67945 -0.305054)
			(end 0.12065 -0.305054)
			(stroke
				(width 0.1)
				(type default)
			)
			(layer "B.Fab")
		)
		(fp_line
			(start 0.67945 0.3048)
			(end 0.67945 -0.305054)
			(stroke
				(width 0.1)
				(type default)
			)
			(layer "B.Fab")
		)
		(pad "1" smd circle
			(at 0.40005 0 180)
			(size 0 0)
			(layers "B.Cu" "B.Mask" "B.Paste")
			(net "PD_CHD_CPU0_DIMM1_SAA")
		)
		(pad "2" smd circle
			(at -0.40005 0 180)
			(size 0 0)
			(layers "B.Cu" "B.Mask" "B.Paste")
			(net "GND")
		)
	)
	(footprint ""
		(layer "B.Cu")
		(at 62.702186 -15.769844 90)
		(property "Reference" "R3216"
			(at 0 0 90)
			(layer "B.SilkS")
			(hide yes)
			(effects
				(font
					(size 1.27 1.27)
				)
				(justify mirror)
			)
		)
		(property "Value" ""
			(at 0 0 90)
			(layer "B.Fab")
			(effects
				(font
					(size 1.27 1.27)
				)
				(justify mirror)
			)
		)
		(duplicate_pad_numbers_are_jumpers no)
		(fp_line
			(start 0.7874 -0.4064)
			(end -0.7874 -0.4064)
			(stroke
				(width 0.1524)
				(type default)
			)
			(layer "B.SilkS")
		)
		(fp_line
			(start -0.7874 -0.4064)
			(end -0.7874 0.4064)
			(stroke
				(width 0.1524)
				(type default)
			)
			(layer "B.SilkS")
		)
		(fp_line
			(start 0.7874 0.4064)
			(end 0.7874 -0.4064)
			(stroke
				(width 0.1524)
				(type default)
			)
			(layer "B.SilkS")
		)
		(fp_line
			(start -0.7874 0.4064)
			(end 0.7874 0.4064)
			(stroke
				(width 0.1524)
				(type default)
			)
			(layer "B.SilkS")
		)
		(fp_line
			(start 0.67945 -0.305054)
			(end 0.12065 -0.305054)
			(stroke
				(width 0.1)
				(type default)
			)
			(layer "B.Fab")
		)
		(fp_line
			(start 0.12065 -0.305054)
			(end 0.12065 -0.2794)
			(stroke
				(width 0.1)
				(type default)
			)
			(layer "B.Fab")
		)
		(fp_line
			(start -0.12065 -0.3048)
			(end -0.67945 -0.3048)
			(stroke
				(width 0.1)
				(type default)
			)
			(layer "B.Fab")
		)
		(fp_line
			(start -0.67945 -0.3048)
			(end -0.67945 0.3048)
			(stroke
				(width 0.1)
				(type default)
			)
			(layer "B.Fab")
		)
		(fp_line
			(start 0.12065 -0.2794)
			(end -0.12065 -0.2794)
			(stroke
				(width 0.1)
				(type default)
			)
			(layer "B.Fab")
		)
		(fp_line
			(start -0.12065 -0.2794)
			(end -0.12065 -0.3048)
			(stroke
				(width 0.1)
				(type default)
			)
			(layer "B.Fab")
		)
		(fp_line
			(start 0.12065 0.2794)
			(end 0.12065 0.3048)
			(stroke
				(width 0.1)
				(type default)
			)
			(layer "B.Fab")
		)
		(fp_line
			(start -0.120396 0.2794)
			(end 0.12065 0.2794)
			(stroke
				(width 0.1)
				(type default)
			)
			(layer "B.Fab")
		)
		(fp_line
			(start 0.67945 0.3048)
			(end 0.67945 -0.305054)
			(stroke
				(width 0.1)
				(type default)
			)
			(layer "B.Fab")
		)
		(fp_line
			(start 0.12065 0.3048)
			(end 0.67945 0.3048)
			(stroke
				(width 0.1)
				(type default)
			)
			(layer "B.Fab")
		)
		(fp_line
			(start -0.120396 0.3048)
			(end -0.120396 0.2794)
			(stroke
				(width 0.1)
				(type default)
			)
			(layer "B.Fab")
		)
		(fp_line
			(start -0.67945 0.3048)
			(end -0.120396 0.3048)
			(stroke
				(width 0.1)
				(type default)
			)
			(layer "B.Fab")
		)
		(pad "1" smd circle
			(at 0.40005 0 270)
			(size 0 0)
			(layers "B.Cu" "B.Mask" "B.Paste")
			(net "OCP_V3_2_ISO_BIF1_EN")
		)
		(pad "2" smd circle
			(at -0.40005 0 270)
			(size 0 0)
			(layers "B.Cu" "B.Mask" "B.Paste")
			(net "GND")
		)
	)
	(footprint ""
		(layer "B.Cu")
		(at 111.490506 -358.522016)
		(property "Reference" "PR453"
			(at 0 0 0)
			(layer "B.SilkS")
			(hide yes)
			(effects
				(font
					(size 1.27 1.27)
				)
				(justify mirror)
			)
		)
		(property "Value" ""
			(at 0 0 0)
			(layer "B.Fab")
			(effects
				(font
					(size 1.27 1.27)
				)
				(justify mirror)
			)
		)
		(duplicate_pad_numbers_are_jumpers no)
		(fp_line
			(start -0.7874 -0.4064)
			(end -0.7874 0.4064)
			(stroke
				(width 0.1524)
				(type default)
			)
			(layer "B.SilkS")
		)
		(fp_line
			(start -0.7874 0.4064)
			(end 0.7874 0.4064)
			(stroke
				(width 0.1524)
				(type default)
			)
			(layer "B.SilkS")
		)
		(fp_line
			(start 0.7874 -0.4064)
			(end -0.7874 -0.4064)
			(stroke
				(width 0.1524)
				(type default)
			)
			(layer "B.SilkS")
		)
		(fp_line
			(start 0.7874 0.4064)
			(end 0.7874 -0.4064)
			(stroke
				(width 0.1524)
				(type default)
			)
			(layer "B.SilkS")
		)
		(fp_line
			(start -0.67945 -0.3048)
			(end -0.67945 0.3048)
			(stroke
				(width 0.1)
				(type default)
			)
			(layer "B.Fab")
		)
		(fp_line
			(start -0.67945 0.3048)
			(end -0.120396 0.3048)
			(stroke
				(width 0.1)
				(type default)
			)
			(layer "B.Fab")
		)
		(fp_line
			(start -0.12065 -0.3048)
			(end -0.67945 -0.3048)
			(stroke
				(width 0.1)
				(type default)
			)
			(layer "B.Fab")
		)
		(fp_line
			(start -0.12065 -0.2794)
			(end -0.12065 -0.3048)
			(stroke
				(width 0.1)
				(type default)
			)
			(layer "B.Fab")
		)
		(fp_line
			(start -0.120396 0.2794)
			(end 0.12065 0.2794)
			(stroke
				(width 0.1)
				(type default)
			)
			(layer "B.Fab")
		)
		(fp_line
			(start -0.120396 0.3048)
			(end -0.120396 0.2794)
			(stroke
				(width 0.1)
				(type default)
			)
			(layer "B.Fab")
		)
		(fp_line
			(start 0.12065 -0.305054)
			(end 0.12065 -0.2794)
			(stroke
				(width 0.1)
				(type default)
			)
			(layer "B.Fab")
		)
		(fp_line
			(start 0.12065 -0.2794)
			(end -0.12065 -0.2794)
			(stroke
				(width 0.1)
				(type default)
			)
			(layer "B.Fab")
		)
		(fp_line
			(start 0.12065 0.2794)
			(end 0.12065 0.3048)
			(stroke
				(width 0.1)
				(type default)
			)
			(layer "B.Fab")
		)
		(fp_line
			(start 0.12065 0.3048)
			(end 0.67945 0.3048)
			(stroke
				(width 0.1)
				(type default)
			)
			(layer "B.Fab")
		)
		(fp_line
			(start 0.67945 -0.305054)
			(end 0.12065 -0.305054)
			(stroke
				(width 0.1)
				(type default)
			)
			(layer "B.Fab")
		)
		(fp_line
			(start 0.67945 0.3048)
			(end 0.67945 -0.305054)
			(stroke
				(width 0.1)
				(type default)
			)
			(layer "B.Fab")
		)
		(pad "1" smd circle
			(at 0.40005 0 180)
			(size 0 0)
			(layers "B.Cu" "B.Mask" "B.Paste")
			(net "PVCCFA_EHV_FIVRA_CPU1_BTSEN")
		)
		(pad "2" smd circle
			(at -0.40005 0 180)
			(size 0 0)
			(layers "B.Cu" "B.Mask" "B.Paste")
			(net "GND")
		)
	)
	(footprint ""
		(layer "B.Cu")
		(at 298.47413 -403.031452 90)
		(property "Reference" "PR2510"
			(at 0 0 90)
			(layer "B.SilkS")
			(hide yes)
			(effects
				(font
					(size 1.27 1.27)
				)
				(justify mirror)
			)
		)
		(property "Value" ""
			(at 0 0 90)
			(layer "B.Fab")
			(effects
				(font
					(size 1.27 1.27)
				)
				(justify mirror)
			)
		)
		(duplicate_pad_numbers_are_jumpers no)
		(fp_line
			(start 0.7874 -0.4064)
			(end -0.7874 -0.4064)
			(stroke
				(width 0.1524)
				(type default)
			)
			(layer "B.SilkS")
		)
		(fp_line
			(start -0.7874 -0.4064)
			(end -0.7874 0.4064)
			(stroke
				(width 0.1524)
				(type default)
			)
			(layer "B.SilkS")
		)
		(fp_line
			(start 0.7874 0.4064)
			(end 0.7874 -0.4064)
			(stroke
				(width 0.1524)
				(type default)
			)
			(layer "B.SilkS")
		)
		(fp_line
			(start -0.7874 0.4064)
			(end 0.7874 0.4064)
			(stroke
				(width 0.1524)
				(type default)
			)
			(layer "B.SilkS")
		)
		(fp_line
			(start 0.67945 -0.305054)
			(end 0.12065 -0.305054)
			(stroke
				(width 0.1)
				(type default)
			)
			(layer "B.Fab")
		)
		(fp_line
			(start 0.12065 -0.305054)
			(end 0.12065 -0.2794)
			(stroke
				(width 0.1)
				(type default)
			)
			(layer "B.Fab")
		)
		(fp_line
			(start -0.12065 -0.3048)
			(end -0.67945 -0.3048)
			(stroke
				(width 0.1)
				(type default)
			)
			(layer "B.Fab")
		)
		(fp_line
			(start -0.67945 -0.3048)
			(end -0.67945 0.3048)
			(stroke
				(width 0.1)
				(type default)
			)
			(layer "B.Fab")
		)
		(fp_line
			(start 0.12065 -0.2794)
			(end -0.12065 -0.2794)
			(stroke
				(width 0.1)
				(type default)
			)
			(layer "B.Fab")
		)
		(fp_line
			(start -0.12065 -0.2794)
			(end -0.12065 -0.3048)
			(stroke
				(width 0.1)
				(type default)
			)
			(layer "B.Fab")
		)
		(fp_line
			(start 0.12065 0.2794)
			(end 0.12065 0.3048)
			(stroke
				(width 0.1)
				(type default)
			)
			(layer "B.Fab")
		)
		(fp_line
			(start -0.120396 0.2794)
			(end 0.12065 0.2794)
			(stroke
				(width 0.1)
				(type default)
			)
			(layer "B.Fab")
		)
		(fp_line
			(start 0.67945 0.3048)
			(end 0.67945 -0.305054)
			(stroke
				(width 0.1)
				(type default)
			)
			(layer "B.Fab")
		)
		(fp_line
			(start 0.12065 0.3048)
			(end 0.67945 0.3048)
			(stroke
				(width 0.1)
				(type default)
			)
			(layer "B.Fab")
		)
		(fp_line
			(start -0.120396 0.3048)
			(end -0.120396 0.2794)
			(stroke
				(width 0.1)
				(type default)
			)
			(layer "B.Fab")
		)
		(fp_line
			(start -0.67945 0.3048)
			(end -0.120396 0.3048)
			(stroke
				(width 0.1)
				(type default)
			)
			(layer "B.Fab")
		)
		(pad "1" smd circle
			(at 0.40005 0 270)
			(size 0 0)
			(layers "B.Cu" "B.Mask" "B.Paste")
			(net "P12V_HSC_ADC_P")
		)
		(pad "2" smd circle
			(at -0.40005 0 270)
			(size 0 0)
			(layers "B.Cu" "B.Mask" "B.Paste")
			(net "P12V_HSC_SENSE2_R1_P")
		)
	)
	(footprint ""
		(layer "B.Cu")
		(at 355.397308 -237.967266 -90)
		(property "Reference" "C395"
			(at 0 0 90)
			(layer "B.SilkS")
			(hide yes)
			(effects
				(font
					(size 1.27 1.27)
				)
				(justify mirror)
			)
		)
		(property "Value" ""
			(at 0 0 90)
			(layer "B.Fab")
			(effects
				(font
					(size 1.27 1.27)
				)
				(justify mirror)
			)
		)
		(duplicate_pad_numbers_are_jumpers no)
		(fp_line
			(start -1.524 0.762)
			(end 1.524 0.762)
			(stroke
				(width 0.1524)
				(type default)
			)
			(layer "B.SilkS")
		)
		(fp_line
			(start 1.524 0.762)
			(end 1.524 -0.762)
			(stroke
				(width 0.1524)
				(type default)
			)
			(layer "B.SilkS")
		)
		(fp_line
			(start -1.524 -0.762)
			(end -1.524 0.762)
			(stroke
				(width 0.1524)
				(type default)
			)
			(layer "B.SilkS")
		)
		(fp_line
			(start 1.524 -0.762)
			(end -1.524 -0.762)
			(stroke
				(width 0.1524)
				(type default)
			)
			(layer "B.SilkS")
		)
		(fp_line
			(start -1.1049 0.724916)
			(end -1.1049 -0.724916)
			(stroke
				(width 0.1)
				(type default)
			)
			(layer "B.Fab")
		)
		(fp_line
			(start 1.1049 0.724916)
			(end -1.1049 0.724916)
			(stroke
				(width 0.1)
				(type default)
			)
			(layer "B.Fab")
		)
		(fp_line
			(start -1.1049 -0.724916)
			(end 1.1049 -0.724916)
			(stroke
				(width 0.1)
				(type default)
			)
			(layer "B.Fab")
		)
		(fp_line
			(start 1.1049 -0.724916)
			(end 1.1049 0.724916)
			(stroke
				(width 0.1)
				(type default)
			)
			(layer "B.Fab")
		)
		(pad "1" smd rect
			(at 0.889 0 270)
			(size 1.016 1.27)
			(layers "B.Cu" "B.Mask" "B.Paste")
			(net "PVNN_MAIN_CPU0")
		)
		(pad "2" smd rect
			(at -0.889 0 270)
			(size 1.016 1.27)
			(layers "B.Cu" "B.Mask" "B.Paste")
			(net "GND")
		)
	)
	(footprint ""
		(layer "B.Cu")
		(at 320.886582 -66.955924 -90)
		(property "Reference" "C1243"
			(at 0 0 90)
			(layer "B.SilkS")
			(hide yes)
			(effects
				(font
					(size 1.27 1.27)
				)
				(justify mirror)
			)
		)
		(property "Value" ""
			(at 0 0 90)
			(layer "B.Fab")
			(effects
				(font
					(size 1.27 1.27)
				)
				(justify mirror)
			)
		)
		(duplicate_pad_numbers_are_jumpers no)
		(fp_line
			(start -1.524 0.762)
			(end 1.524 0.762)
			(stroke
				(width 0.1524)
				(type default)
			)
			(layer "B.SilkS")
		)
		(fp_line
			(start 1.524 0.762)
			(end 1.524 -0.762)
			(stroke
				(width 0.1524)
				(type default)
			)
			(layer "B.SilkS")
		)
		(fp_line
			(start -1.524 -0.762)
			(end -1.524 0.762)
			(stroke
				(width 0.1524)
				(type default)
			)
			(layer "B.SilkS")
		)
		(fp_line
			(start 1.524 -0.762)
			(end -1.524 -0.762)
			(stroke
				(width 0.1524)
				(type default)
			)
			(layer "B.SilkS")
		)
		(fp_line
			(start -1.1049 0.724916)
			(end -1.1049 -0.724916)
			(stroke
				(width 0.1)
				(type default)
			)
			(layer "B.Fab")
		)
		(fp_line
			(start 1.1049 0.724916)
			(end -1.1049 0.724916)
			(stroke
				(width 0.1)
				(type default)
			)
			(layer "B.Fab")
		)
		(fp_line
			(start -1.1049 -0.724916)
			(end 1.1049 -0.724916)
			(stroke
				(width 0.1)
				(type default)
			)
			(layer "B.Fab")
		)
		(fp_line
			(start 1.1049 -0.724916)
			(end 1.1049 0.724916)
			(stroke
				(width 0.1)
				(type default)
			)
			(layer "B.Fab")
		)
		(pad "1" smd rect
			(at 0.889 0 270)
			(size 1.016 1.27)
			(layers "B.Cu" "B.Mask" "B.Paste")
			(net "P3V3_AUX")
		)
		(pad "2" smd rect
			(at -0.889 0 270)
			(size 1.016 1.27)
			(layers "B.Cu" "B.Mask" "B.Paste")
			(net "GND")
		)
	)
	(footprint ""
		(layer "B.Cu")
		(at 339.244686 -45.481748 180)
		(property "Reference" "C1256"
			(at 0 0 0)
			(layer "B.SilkS")
			(hide yes)
			(effects
				(font
					(size 1.27 1.27)
				)
				(justify mirror)
			)
		)
		(property "Value" ""
			(at 0 0 0)
			(layer "B.Fab")
			(effects
				(font
					(size 1.27 1.27)
				)
				(justify mirror)
			)
		)
		(duplicate_pad_numbers_are_jumpers no)
		(fp_line
			(start 0.7874 0.4064)
			(end 0.7874 -0.4064)
			(stroke
				(width 0.1524)
				(type default)
			)
			(layer "B.SilkS")
		)
		(fp_line
			(start 0.7874 -0.4064)
			(end -0.7874 -0.4064)
			(stroke
				(width 0.1524)
				(type default)
			)
			(layer "B.SilkS")
		)
		(fp_line
			(start -0.7874 0.4064)
			(end 0.7874 0.4064)
			(stroke
				(width 0.1524)
				(type default)
			)
			(layer "B.SilkS")
		)
		(fp_line
			(start -0.7874 -0.4064)
			(end -0.7874 0.4064)
			(stroke
				(width 0.1524)
				(type default)
			)
			(layer "B.SilkS")
		)
		(fp_line
			(start 0.67945 0.3048)
			(end 0.67945 -0.305054)
			(stroke
				(width 0.1)
				(type default)
			)
			(layer "B.Fab")
		)
		(fp_line
			(start 0.67945 -0.305054)
			(end 0.12065 -0.305054)
			(stroke
				(width 0.1)
				(type default)
			)
			(layer "B.Fab")
		)
		(fp_line
			(start 0.12065 0.3048)
			(end 0.67945 0.3048)
			(stroke
				(width 0.1)
				(type default)
			)
			(layer "B.Fab")
		)
		(fp_line
			(start 0.12065 0.2794)
			(end 0.12065 0.3048)
			(stroke
				(width 0.1)
				(type default)
			)
			(layer "B.Fab")
		)
		(fp_line
			(start 0.12065 -0.2794)
			(end -0.12065 -0.2794)
			(stroke
				(width 0.1)
				(type default)
			)
			(layer "B.Fab")
		)
		(fp_line
			(start 0.12065 -0.305054)
			(end 0.12065 -0.2794)
			(stroke
				(width 0.1)
				(type default)
			)
			(layer "B.Fab")
		)
		(fp_line
			(start -0.120396 0.3048)
			(end -0.120396 0.2794)
			(stroke
				(width 0.1)
				(type default)
			)
			(layer "B.Fab")
		)
		(fp_line
			(start -0.120396 0.2794)
			(end 0.12065 0.2794)
			(stroke
				(width 0.1)
				(type default)
			)
			(layer "B.Fab")
		)
		(fp_line
			(start -0.12065 -0.2794)
			(end -0.12065 -0.3048)
			(stroke
				(width 0.1)
				(type default)
			)
			(layer "B.Fab")
		)
		(fp_line
			(start -0.12065 -0.3048)
			(end -0.67945 -0.3048)
			(stroke
				(width 0.1)
				(type default)
			)
			(layer "B.Fab")
		)
		(fp_line
			(start -0.67945 0.3048)
			(end -0.120396 0.3048)
			(stroke
				(width 0.1)
				(type default)
			)
			(layer "B.Fab")
		)
		(fp_line
			(start -0.67945 -0.3048)
			(end -0.67945 0.3048)
			(stroke
				(width 0.1)
				(type default)
			)
			(layer "B.Fab")
		)
		(pad "1" smd circle
			(at 0.40005 0)
			(size 0 0)
			(layers "B.Cu" "B.Mask" "B.Paste")
			(net "P1V05_PCH_PLL_AUX")
		)
		(pad "2" smd circle
			(at -0.40005 0)
			(size 0 0)
			(layers "B.Cu" "B.Mask" "B.Paste")
			(net "GND")
		)
	)
)
